# S9S_MB_2U (Grand Teton) — schematic netlist excerpt (pin names and nets, part order shuffled) for the footprints in the layout excerpt that follows; sources: Cadence DE-HDL packaged netlist, KiCad conversion of 03242023_DA0F0TMBIJ0_F0T_Motherboard_J_brd_V01_OCP.brd

R418  Q_RES  0 5% CHIP  pkg 0402LF  page 153 : A = OCP_SFF_ISO_BIF2_EN ; B = OCP_SFF_BIF2_R_N

(kicad_pcb
	(version 20260206)
	(generator "pcbnew")
	(generator_version "10.0")
	(general
		(thickness 1.6)
		(legacy_teardrops no)
	)
	(paper "A4")
	(title_block
		(title "03242023_DA0F0TMBIJ0_F0T_Motherboard_J_brd_V01_OCP.brd")
		(comment 1 "Grand Teton / footprints 2538-2538 of 6105")
	)
	(layers
		(0 "F.Cu" signal "TOP")
		(4 "In1.Cu" signal "GND")
		(6 "In2.Cu" signal "IN1")
		(8 "In3.Cu" signal "GND1")
		(10 "In4.Cu" signal "IN2")
		(12 "In5.Cu" signal "GND2")
		(14 "In6.Cu" signal "IN3")
		(16 "In7.Cu" signal "GND3")
		(18 "In8.Cu" signal "VCC")
		(20 "In9.Cu" signal "VCC1")
		(22 "In10.Cu" signal "GND4")
		(24 "In11.Cu" signal "IN4")
		(26 "In12.Cu" signal "GND5")
		(28 "In13.Cu" signal "IN5")
		(30 "In14.Cu" signal "GND6")
		(32 "In15.Cu" signal "IN6")
		(34 "In16.Cu" signal "GND7")
		(2 "B.Cu" signal "BOTTOM")
		(9 "F.Adhes" user "F.Adhesive")
		(11 "B.Adhes" user "B.Adhesive")
		(13 "F.Paste" user "Package Geometry/Pastemask Top")
		(15 "B.Paste" user "Package Geometry/Pastemask Bottom")
		(5 "F.SilkS" user "Ref Des/Silkscreen Top")
		(7 "B.SilkS" user "Ref Des/Silkscreen Bottom")
		(1 "F.Mask" user "Board Geometry/Soldermask Top")
		(3 "B.Mask" user "Board Geometry/Soldermask Bottom")
		(17 "Dwgs.User" user "User.Drawings")
		(19 "Cmts.User" user "User.Comments")
		(21 "Eco1.User" user "User.Eco1")
		(23 "Eco2.User" user "User.Eco2")
		(25 "Edge.Cuts" user "Board Geometry/Outline")
		(27 "Margin" user)
		(31 "F.CrtYd" user "Package Geometry/Place Bound Top")
		(29 "B.CrtYd" user "Package Geometry/Place Bound Bottom")
		(35 "F.Fab" user "Ref Des/Assembly Top")
		(33 "B.Fab" user "Ref Des/Assembly Bottom")
	)
	(footprint ""
		(layer "F.Cu")
		(at 437.10733 -16.248126 -90)
		(property "Reference" "R418"
			(at 0 0 270)
			(layer "F.SilkS")
			(hide yes)
			(effects
				(font
					(size 1.27 1.27)
				)
			)
		)
		(property "Value" ""
			(at 0 0 270)
			(layer "F.Fab")
			(effects
				(font
					(size 1.27 1.27)
				)
			)
		)
		(duplicate_pad_numbers_are_jumpers no)
		(fp_line
			(start -0.7874 0.4064)
			(end -0.7874 -0.4064)
			(stroke
				(width 0.1524)
				(type default)
			)
			(layer "F.SilkS")
		)
		(fp_line
			(start 0.7874 0.4064)
			(end -0.7874 0.4064)
			(stroke
				(width 0.1524)
				(type default)
			)
			(layer "F.SilkS")
		)
		(fp_line
			(start -0.7874 -0.4064)
			(end 0.7874 -0.4064)
			(stroke
				(width 0.1524)
				(type default)
			)
			(layer "F.SilkS")
		)
		(fp_line
			(start 0.7874 -0.4064)
			(end 0.7874 0.4064)
			(stroke
				(width 0.1524)
				(type default)
			)
			(layer "F.SilkS")
		)
		(fp_line
			(start -0.67945 0.3048)
			(end -0.67945 -0.305054)
			(stroke
				(width 0.1)
				(type default)
			)
			(layer "F.Fab")
		)
		(fp_line
			(start -0.12065 0.3048)
			(end -0.67945 0.3048)
			(stroke
				(width 0.1)
				(type default)
			)
			(layer "F.Fab")
		)
		(fp_line
			(start 0.120396 0.3048)
			(end 0.120396 0.2794)
			(stroke
				(width 0.1)
				(type default)
			)
			(layer "F.Fab")
		)
		(fp_line
			(start 0.67945 0.3048)
			(end 0.120396 0.3048)
			(stroke
				(width 0.1)
				(type default)
			)
			(layer "F.Fab")
		)
		(fp_line
			(start -0.12065 0.2794)
			(end -0.12065 0.3048)
			(stroke
				(width 0.1)
				(type default)
			)
			(layer "F.Fab")
		)
		(fp_line
			(start 0.120396 0.2794)
			(end -0.12065 0.2794)
			(stroke
				(width 0.1)
				(type default)
			)
			(layer "F.Fab")
		)
		(fp_line
			(start -0.12065 -0.2794)
			(end 0.12065 -0.2794)
			(stroke
				(width 0.1)
				(type default)
			)
			(layer "F.Fab")
		)
		(fp_line
			(start 0.12065 -0.2794)
			(end 0.12065 -0.3048)
			(stroke
				(width 0.1)
				(type default)
			)
			(layer "F.Fab")
		)
		(fp_line
			(start 0.12065 -0.3048)
			(end 0.67945 -0.3048)
			(stroke
				(width 0.1)
				(type default)
			)
			(layer "F.Fab")
		)
		(fp_line
			(start 0.67945 -0.3048)
			(end 0.67945 0.3048)
			(stroke
				(width 0.1)
				(type default)
			)
			(layer "F.Fab")
		)
		(fp_line
			(start -0.67945 -0.305054)
			(end -0.12065 -0.305054)
			(stroke
				(width 0.1)
				(type default)
			)
			(layer "F.Fab")
		)
		(fp_line
			(start -0.12065 -0.305054)
			(end -0.12065 -0.2794)
			(stroke
				(width 0.1)
				(type default)
			)
			(layer "F.Fab")
		)
		(pad "1" smd circle
			(at -0.40005 0 270)
			(size 0 0)
			(layers "F.Cu" "F.Mask" "F.Paste")
			(net "OCP_SFF_ISO_BIF2_EN")
		)
		(pad "2" smd circle
			(at 0.40005 0 270)
			(size 0 0)
			(layers "F.Cu" "F.Mask" "F.Paste")
			(net "OCP_SFF_BIF2_R_N")
		)
	)
)
